(kicad_pcb
	(version 20260206)
	(generator "pcbnew")
	(generator_version "10.0")
	(general
		(thickness 1.6)
		(legacy_teardrops no)
	)
	(paper "A4")
	(title_block
		(title "Bryce Canyon_R.DPB_16317-1_OCP.brd")
		(comment 1 "Bryce Canyon / footprints 738-745 of 2099")
	)
	(layers
		(0 "F.Cu" signal "TOP")
		(4 "In1.Cu" signal "L2GND")
		(6 "In2.Cu" signal "L3")
		(8 "In3.Cu" signal "L4VCC")
		(10 "In4.Cu" signal "L5VCC")
		(12 "In5.Cu" signal "L6")
		(14 "In6.Cu" signal "L7GND")
		(2 "B.Cu" signal "BOTTOM")
		(9 "F.Adhes" user "F.Adhesive")
		(11 "B.Adhes" user "B.Adhesive")
		(13 "F.Paste" user "Package Geometry/Pastemask Top")
		(15 "B.Paste" user "Package Geometry/Pastemask Bottom")
		(5 "F.SilkS" user "Ref Des/Silkscreen Top")
		(7 "B.SilkS" user "Ref Des/Silkscreen Bottom")
		(1 "F.Mask" user "Board Geometry/Soldermask Top")
		(3 "B.Mask" user "Board Geometry/Soldermask Bottom")
		(17 "Dwgs.User" user "User.Drawings")
		(19 "Cmts.User" user "User.Comments")
		(21 "Eco1.User" user "User.Eco1")
		(23 "Eco2.User" user "User.Eco2")
		(25 "Edge.Cuts" user "Board Geometry/Outline")
		(27 "Margin" user)
		(31 "F.CrtYd" user "Package Geometry/Place Bound Top")
		(29 "B.CrtYd" user "Package Geometry/Place Bound Bottom")
		(35 "F.Fab" user "Ref Des/Assembly Top")
		(33 "B.Fab" user "Ref Des/Assembly Bottom")
	)
	(footprint ""
		(layer "F.Cu")
		(at 261.1247 -376.761756 180)
		(property "Reference" "Q210"
			(at 0 0 180)
			(layer "F.SilkS")
			(hide yes)
			(effects
				(font
					(size 1.27 1.27)
				)
			)
		)
		(property "Value" "MMBT2222A-3-GP"
			(at 0.10287 -10.29843 180)
			(unlocked yes)
			(layer "F.Fab")
			(hide yes)
			(effects
				(font
					(size 1.016 1.016)
					(thickness 0.1524)
				)
			)
		)
		(property "Device Type" "SOT23CBE2D4H44"
			(at 0.10287 -12.20343 180)
			(unlocked yes)
			(layer "F.Fab")
			(hide yes)
			(effects
				(font
					(size 1.016 1.016)
					(thickness 0.1524)
				)
			)
		)
		(duplicate_pad_numbers_are_jumpers no)
		(fp_line
			(start 1.651 1.778)
			(end 1.651 -1.778)
			(stroke
				(width 0.1524)
				(type default)
			)
			(layer "F.SilkS")
		)
		(fp_line
			(start 1.651 -1.778)
			(end -1.651 -1.778)
			(stroke
				(width 0.1524)
				(type default)
			)
			(layer "F.SilkS")
		)
		(fp_line
			(start -1.651 1.778)
			(end 1.651 1.778)
			(stroke
				(width 0.1524)
				(type default)
			)
			(layer "F.SilkS")
		)
		(fp_line
			(start -1.651 -1.778)
			(end -1.651 1.778)
			(stroke
				(width 0.1524)
				(type default)
			)
			(layer "F.SilkS")
		)
		(fp_poly
			(pts
				(xy -1.778 1.8796) (xy -1.778 -1.8796) (xy 1.778 -1.8796) (xy 1.778 1.8796)
			)
			(stroke
				(width 0)
				(type default)
			)
			(fill no)
			(layer "F.CrtYd")
		)
		(fp_poly
			(pts
				(xy -1.778 1.8796) (xy -1.778 -1.8796) (xy 1.778 -1.8796) (xy 1.778 1.8796)
			)
			(stroke
				(width 0)
				(type default)
			)
			(fill no)
			(layer "F.Fab")
		)
		(pad "B" smd custom
			(at -0.98425 0.9525 180)
			(size 0.1905 0.1905)
			(layers "F.Cu" "F.Mask" "F.Paste")
			(net "DRAWER_OUT_NET_B")
			(options
				(clearance outline)
				(anchor circle)
			)
			(primitives
				(gr_poly
					(pts
						(arc
							(start -0.1778 0.5715)
							(mid -0.321484 0.511984)
							(end -0.381 0.3683)
						)
						(arc
							(start -0.381 -0.3683)
							(mid -0.321484 -0.511984)
							(end -0.1778 -0.5715)
						)
						(arc
							(start 0.1778 -0.5715)
							(mid 0.321484 -0.511984)
							(end 0.381 -0.3683)
						)
						(arc
							(start 0.381 0.3683)
							(mid 0.321484 0.511984)
							(end 0.1778 0.5715)
						)
					)
					(width 0)
					(fill yes)
				)
			)
		)
		(pad "C" smd custom
			(at 0 -0.9525 180)
			(size 0.1905 0.1905)
			(layers "F.Cu" "F.Mask" "F.Paste")
			(net "DRAWER_OUT#_C")
			(options
				(clearance outline)
				(anchor circle)
			)
			(primitives
				(gr_poly
					(pts
						(arc
							(start -0.1778 0.5715)
							(mid -0.321484 0.511984)
							(end -0.381 0.3683)
						)
						(arc
							(start -0.381 -0.3683)
							(mid -0.321484 -0.511984)
							(end -0.1778 -0.5715)
						)
						(arc
							(start 0.1778 -0.5715)
							(mid 0.321484 -0.511984)
							(end 0.381 -0.3683)
						)
						(arc
							(start 0.381 0.3683)
							(mid 0.321484 0.511984)
							(end 0.1778 0.5715)
						)
					)
					(width 0)
					(fill yes)
				)
			)
		)
		(pad "E" smd custom
			(at 0.98425 0.9525 180)
			(size 0.1905 0.1905)
			(layers "F.Cu" "F.Mask" "F.Paste")
			(net "GND")
			(options
				(clearance outline)
				(anchor circle)
			)
			(primitives
				(gr_poly
					(pts
						(arc
							(start -0.1778 0.5715)
							(mid -0.321484 0.511984)
							(end -0.381 0.3683)
						)
						(arc
							(start -0.381 -0.3683)
							(mid -0.321484 -0.511984)
							(end -0.1778 -0.5715)
						)
						(arc
							(start 0.1778 -0.5715)
							(mid 0.321484 -0.511984)
							(end 0.381 -0.3683)
						)
						(arc
							(start 0.381 0.3683)
							(mid 0.321484 0.511984)
							(end 0.1778 0.5715)
						)
					)
					(width 0)
					(fill yes)
				)
			)
		)
	)
	(footprint ""
		(layer "F.Cu")
		(at 158.708852 -248.750074 -90)
		(property "Reference" "VIA10"
			(at 0 0 270)
			(layer "F.SilkS")
			(hide yes)
			(effects
				(font
					(size 1.27 1.27)
				)
			)
		)
		(property "Value" "100OHM-8L-2D36MM-L16-GP"
			(at -3.4036 -0.4572 270)
			(unlocked yes)
			(layer "F.Fab")
			(hide yes)
			(effects
				(font
					(size 1.016 1.016)
					(thickness 0.1524)
				)
			)
		)
		(property "Device Type" "VIA-PCIE-4P-427097"
			(at -3.4036 -1.9812 270)
			(unlocked yes)
			(layer "F.Fab")
			(hide yes)
			(effects
				(font
					(size 1.016 1.016)
					(thickness 0.1524)
				)
			)
		)
		(duplicate_pad_numbers_are_jumpers no)
		(fp_rect
			(start -2.1336 0.4826)
			(end 2.1336 -0.4826)
			(stroke
				(width 0)
				(type default)
			)
			(fill no)
			(layer "F.CrtYd")
		)
		(fp_rect
			(start -2.1336 0.4826)
			(end 2.1336 -0.4826)
			(stroke
				(width 0)
				(type default)
			)
			(fill no)
			(layer "F.Fab")
		)
		(pad "1" thru_hole circle
			(at -1.651 0 270)
			(size 0.508 0.508)
			(drill 0.254)
			(layers "*.Cu" "*.Mask")
			(remove_unused_layers no)
			(net "GND")
			(clearance 0.2286)
			(thermal_gap 0.2286)
		)
		(pad "2" thru_hole circle
			(at -0.635 0 270)
			(size 0.508 0.508)
			(drill 0.254)
			(layers "*.Cu" "*.Mask")
			(remove_unused_layers no)
			(net "PHY_DRV_B_TO_SCC_B_4_DP")
			(clearance 0.2286)
			(thermal_gap 0.2286)
		)
		(pad "3" thru_hole circle
			(at 0.635 0 270)
			(size 0.508 0.508)
			(drill 0.254)
			(layers "*.Cu" "*.Mask")
			(remove_unused_layers no)
			(net "PHY_DRV_B_TO_SCC_B_4_DN")
			(clearance 0.2286)
			(thermal_gap 0.2286)
		)
		(pad "4" thru_hole circle
			(at 1.651 0 270)
			(size 0.508 0.508)
			(drill 0.254)
			(layers "*.Cu" "*.Mask")
			(remove_unused_layers no)
			(net "GND")
			(clearance 0.2286)
			(thermal_gap 0.2286)
		)
	)
	(footprint ""
		(layer "F.Cu")
		(at 98.425 -148.082 -90)
		(property "Reference" "R392"
			(at 0 0 270)
			(layer "F.SilkS")
			(hide yes)
			(effects
				(font
					(size 1.27 1.27)
				)
			)
		)
		(property "Value" "10KR2F-2-GP"
			(at 0.064008 -3.993896 270)
			(unlocked yes)
			(layer "F.Fab")
			(hide yes)
			(effects
				(font
					(size 1.016 1.016)
					(thickness 0.1524)
				)
			)
		)
		(property "Device Type" "R402H16"
			(at 0.064008 -5.517896 270)
			(unlocked yes)
			(layer "F.Fab")
			(hide yes)
			(effects
				(font
					(size 1.016 1.016)
					(thickness 0.1524)
				)
			)
		)
		(duplicate_pad_numbers_are_jumpers no)
		(fp_line
			(start -0.508 -0.9398)
			(end -0.508 0.9398)
			(stroke
				(width 0.1524)
				(type default)
			)
			(layer "F.SilkS")
		)
		(fp_line
			(start 0.508 -0.9398)
			(end -0.508 -0.9398)
			(stroke
				(width 0.1524)
				(type default)
			)
			(layer "F.SilkS")
		)
		(fp_rect
			(start -0.508 0.9398)
			(end 0.508 -0.9398)
			(stroke
				(width 0)
				(type default)
			)
			(fill no)
			(layer "F.CrtYd")
		)
		(fp_rect
			(start -0.508 0.9398)
			(end 0.508 -0.9398)
			(stroke
				(width 0)
				(type default)
			)
			(fill no)
			(layer "F.Fab")
		)
		(pad "1" smd custom
			(at 0 -0.4445 270)
			(size 0.1397 0.1397)
			(layers "F.Cu" "F.Mask" "F.Paste")
			(net "P3V3_STBY_B")
			(options
				(clearance outline)
				(anchor circle)
			)
			(primitives
				(gr_poly
					(pts
						(arc
							(start -0.1778 -0.2794)
							(mid -0.249642 -0.249642)
							(end -0.2794 -0.1778)
						)
						(arc
							(start -0.2794 0.1778)
							(mid -0.249642 0.249642)
							(end -0.1778 0.2794)
						)
						(arc
							(start 0.1778 0.2794)
							(mid 0.249642 0.249642)
							(end 0.2794 0.1778)
						)
						(arc
							(start 0.2794 -0.1778)
							(mid 0.249642 -0.249642)
							(end 0.1778 -0.2794)
						)
					)
					(width 0)
					(fill yes)
				)
			)
		)
		(pad "2" smd custom
			(at 0 0.4445 270)
			(size 0.1397 0.1397)
			(layers "F.Cu" "F.Mask" "F.Paste")
			(net "HDD_PRSNT_14")
			(options
				(clearance outline)
				(anchor circle)
			)
			(primitives
				(gr_poly
					(pts
						(arc
							(start -0.1778 -0.2794)
							(mid -0.249642 -0.249642)
							(end -0.2794 -0.1778)
						)
						(arc
							(start -0.2794 0.1778)
							(mid -0.249642 0.249642)
							(end -0.1778 0.2794)
						)
						(arc
							(start 0.1778 0.2794)
							(mid 0.249642 0.249642)
							(end 0.2794 0.1778)
						)
						(arc
							(start 0.2794 -0.1778)
							(mid 0.249642 -0.249642)
							(end 0.1778 -0.2794)
						)
					)
					(width 0)
					(fill yes)
				)
			)
		)
	)
	(footprint ""
		(layer "F.Cu")
		(at 22.993096 -374.3071 90)
		(property "Reference" "R965"
			(at 0 0 90)
			(layer "F.SilkS")
			(hide yes)
			(effects
				(font
					(size 1.27 1.27)
				)
			)
		)
		(property "Value" "270R5J-2-GP"
			(at 0 -8.9535 90)
			(unlocked yes)
			(layer "F.Fab")
			(hide yes)
			(effects
				(font
					(size 1.27 1.016)
					(thickness 0.1524)
				)
			)
		)
		(property "Device Type" "R805H24"
			(at 0 -10.6299 90)
			(unlocked yes)
			(layer "F.Fab")
			(hide yes)
			(effects
				(font
					(size 1.27 1.016)
					(thickness 0.1524)
				)
			)
		)
		(duplicate_pad_numbers_are_jumpers no)
		(fp_line
			(start 0.889 -1.7018)
			(end -0.889 -1.7018)
			(stroke
				(width 0.1524)
				(type default)
			)
			(layer "F.SilkS")
		)
		(fp_line
			(start 0.889 -1.7018)
			(end 0.889 -0.381)
			(stroke
				(width 0.1524)
				(type default)
			)
			(layer "F.SilkS")
		)
		(fp_line
			(start -0.889 -1.7018)
			(end -0.889 0.2794)
			(stroke
				(width 0.1524)
				(type default)
			)
			(layer "F.SilkS")
		)
		(fp_line
			(start -0.889 0.0762)
			(end -0.889 1.7018)
			(stroke
				(width 0.1524)
				(type default)
			)
			(layer "F.SilkS")
		)
		(fp_line
			(start 0.889 1.7018)
			(end 0.889 -0.508)
			(stroke
				(width 0.1524)
				(type default)
			)
			(layer "F.SilkS")
		)
		(fp_line
			(start -0.889 1.7018)
			(end 0.889 1.7018)
			(stroke
				(width 0.1524)
				(type default)
			)
			(layer "F.SilkS")
		)
		(fp_poly
			(pts
				(xy 0.9652 -1.778) (xy 0.9652 1.778) (xy -0.9652 1.778) (xy -0.9652 -1.778)
			)
			(stroke
				(width 0)
				(type default)
			)
			(fill no)
			(layer "F.CrtYd")
		)
		(fp_rect
			(start -0.9652 1.778)
			(end 0.9652 -1.778)
			(stroke
				(width 0)
				(type default)
			)
			(fill no)
			(layer "F.Fab")
		)
		(pad "1" smd rect
			(at 0 -0.9652 90)
			(size 1.397 1.143)
			(layers "F.Cu" "F.Mask" "F.Paste")
			(net "FAN_LED_BLUE0")
		)
		(pad "2" smd rect
			(at 0 0.9652 90)
			(size 1.397 1.143)
			(layers "F.Cu" "F.Mask" "F.Paste")
			(net "FAN_BLUE0")
		)
	)
	(footprint ""
		(layer "F.Cu")
		(at 251.776992 -137.04697 -90)
		(property "Reference" "R441"
			(at 0 0 270)
			(layer "F.SilkS")
			(hide yes)
			(effects
				(font
					(size 1.27 1.27)
				)
			)
		)
		(property "Value" "10KR2F-2-GP"
			(at 0.064008 -3.993896 270)
			(unlocked yes)
			(layer "F.Fab")
			(hide yes)
			(effects
				(font
					(size 1.016 1.016)
					(thickness 0.1524)
				)
			)
		)
		(property "Device Type" "R402H16"
			(at 0.064008 -5.517896 270)
			(unlocked yes)
			(layer "F.Fab")
			(hide yes)
			(effects
				(font
					(size 1.016 1.016)
					(thickness 0.1524)
				)
			)
		)
		(duplicate_pad_numbers_are_jumpers no)
		(fp_line
			(start -0.508 -0.9398)
			(end -0.508 0.9398)
			(stroke
				(width 0.1524)
				(type default)
			)
			(layer "F.SilkS")
		)
		(fp_line
			(start 0.508 -0.9398)
			(end -0.508 -0.9398)
			(stroke
				(width 0.1524)
				(type default)
			)
			(layer "F.SilkS")
		)
		(fp_rect
			(start -0.508 0.9398)
			(end 0.508 -0.9398)
			(stroke
				(width 0)
				(type default)
			)
			(fill no)
			(layer "F.CrtYd")
		)
		(fp_rect
			(start -0.508 0.9398)
			(end 0.508 -0.9398)
			(stroke
				(width 0)
				(type default)
			)
			(fill no)
			(layer "F.Fab")
		)
		(pad "1" smd custom
			(at 0 -0.4445 270)
			(size 0.1397 0.1397)
			(layers "F.Cu" "F.Mask" "F.Paste")
			(net "P3V3_STBY_B")
			(options
				(clearance outline)
				(anchor circle)
			)
			(primitives
				(gr_poly
					(pts
						(arc
							(start -0.1778 -0.2794)
							(mid -0.249642 -0.249642)
							(end -0.2794 -0.1778)
						)
						(arc
							(start -0.2794 0.1778)
							(mid -0.249642 0.249642)
							(end -0.1778 0.2794)
						)
						(arc
							(start 0.1778 0.2794)
							(mid 0.249642 0.249642)
							(end 0.2794 0.1778)
						)
						(arc
							(start 0.2794 -0.1778)
							(mid 0.249642 -0.249642)
							(end 0.1778 -0.2794)
						)
					)
					(width 0)
					(fill yes)
				)
			)
		)
		(pad "2" smd custom
			(at 0 0.4445 270)
			(size 0.1397 0.1397)
			(layers "F.Cu" "F.Mask" "F.Paste")
			(net "I2C_SCC_BUFF_READY")
			(options
				(clearance outline)
				(anchor circle)
			)
			(primitives
				(gr_poly
					(pts
						(arc
							(start -0.1778 -0.2794)
							(mid -0.249642 -0.249642)
							(end -0.2794 -0.1778)
						)
						(arc
							(start -0.2794 0.1778)
							(mid -0.249642 0.249642)
							(end -0.1778 0.2794)
						)
						(arc
							(start 0.1778 0.2794)
							(mid 0.249642 0.249642)
							(end 0.2794 0.1778)
						)
						(arc
							(start 0.2794 -0.1778)
							(mid 0.249642 -0.249642)
							(end 0.1778 -0.2794)
						)
					)
					(width 0)
					(fill yes)
				)
			)
		)
	)
	(footprint ""
		(layer "F.Cu")
		(at 361.315 -152.908 180)
		(property "Reference" "C277"
			(at 0 0 180)
			(layer "F.SilkS")
			(hide yes)
			(effects
				(font
					(size 1.27 1.27)
				)
			)
		)
		(property "Value" "SC1U16V3KX-5GP"
			(at 0 -2.8194 180)
			(unlocked yes)
			(layer "F.Fab")
			(hide yes)
			(effects
				(font
					(size 1.016 1.016)
					(thickness 0.1524)
				)
			)
		)
		(property "Device Type" "C603H36"
			(at 0 -4.3434 180)
			(unlocked yes)
			(layer "F.Fab")
			(hide yes)
			(effects
				(font
					(size 1.016 1.016)
					(thickness 0.1524)
				)
			)
		)
		(duplicate_pad_numbers_are_jumpers no)
		(fp_line
			(start 0.508 0)
			(end -0.508 0)
			(stroke
				(width 0.2032)
				(type default)
			)
			(layer "F.SilkS")
		)
		(fp_rect
			(start -0.5842 1.3335)
			(end 0.5842 -1.3335)
			(stroke
				(width 0)
				(type default)
			)
			(fill no)
			(layer "F.CrtYd")
		)
		(fp_rect
			(start -0.5842 1.3335)
			(end 0.5842 -1.3335)
			(stroke
				(width 0)
				(type default)
			)
			(fill no)
			(layer "F.Fab")
		)
		(pad "1" smd custom
			(at 0 -0.762 180)
			(size 0.2159 0.2159)
			(layers "F.Cu" "F.Mask" "F.Paste")
			(net "P5V_HDD19")
			(options
				(clearance outline)
				(anchor circle)
			)
			(primitives
				(gr_poly
					(pts
						(arc
							(start -0.3302 -0.4318)
							(mid -0.402042 -0.402042)
							(end -0.4318 -0.3302)
						)
						(arc
							(start -0.4318 0.3302)
							(mid -0.402042 0.402042)
							(end -0.3302 0.4318)
						)
						(arc
							(start 0.3302 0.4318)
							(mid 0.402042 0.402042)
							(end 0.4318 0.3302)
						)
						(arc
							(start 0.4318 -0.3302)
							(mid 0.402042 -0.402042)
							(end 0.3302 -0.4318)
						)
					)
					(width 0)
					(fill yes)
				)
			)
		)
		(pad "2" smd custom
			(at 0 0.762 180)
			(size 0.2159 0.2159)
			(layers "F.Cu" "F.Mask" "F.Paste")
			(net "GND")
			(options
				(clearance outline)
				(anchor circle)
			)
			(primitives
				(gr_poly
					(pts
						(arc
							(start -0.3302 -0.4318)
							(mid -0.402042 -0.402042)
							(end -0.4318 -0.3302)
						)
						(arc
							(start -0.4318 0.3302)
							(mid -0.402042 0.402042)
							(end -0.3302 0.4318)
						)
						(arc
							(start 0.3302 0.4318)
							(mid 0.402042 0.402042)
							(end 0.4318 0.3302)
						)
						(arc
							(start 0.4318 -0.3302)
							(mid 0.402042 -0.402042)
							(end 0.3302 -0.4318)
						)
					)
					(width 0)
					(fill yes)
				)
			)
		)
	)
	(footprint ""
		(layer "F.Cu")
		(at 180.7464 -248.4882 -90)
		(property "Reference" "R244"
			(at 0 0 270)
			(layer "F.SilkS")
			(hide yes)
			(effects
				(font
					(size 1.27 1.27)
				)
			)
		)
		(property "Value" "1KR2F-3-GP"
			(at 0.064008 -3.993896 270)
			(unlocked yes)
			(layer "F.Fab")
			(hide yes)
			(effects
				(font
					(size 1.016 1.016)
					(thickness 0.1524)
				)
			)
		)
		(property "Device Type" "R402H16"
			(at 0.064008 -5.517896 270)
			(unlocked yes)
			(layer "F.Fab")
			(hide yes)
			(effects
				(font
					(size 1.016 1.016)
					(thickness 0.1524)
				)
			)
		)
		(duplicate_pad_numbers_are_jumpers no)
		(fp_line
			(start -0.508 -0.9398)
			(end -0.508 0.9398)
			(stroke
				(width 0.1524)
				(type default)
			)
			(layer "F.SilkS")
		)
		(fp_line
			(start 0.508 -0.9398)
			(end -0.508 -0.9398)
			(stroke
				(width 0.1524)
				(type default)
			)
			(layer "F.SilkS")
		)
		(fp_rect
			(start -0.508 0.9398)
			(end 0.508 -0.9398)
			(stroke
				(width 0)
				(type default)
			)
			(fill no)
			(layer "F.CrtYd")
		)
		(fp_rect
			(start -0.508 0.9398)
			(end 0.508 -0.9398)
			(stroke
				(width 0)
				(type default)
			)
			(fill no)
			(layer "F.Fab")
		)
		(pad "1" smd custom
			(at 0 -0.4445 270)
			(size 0.1397 0.1397)
			(layers "F.Cu" "F.Mask" "F.Paste")
			(net "P3V3_STBY_B")
			(options
				(clearance outline)
				(anchor circle)
			)
			(primitives
				(gr_poly
					(pts
						(arc
							(start -0.1778 -0.2794)
							(mid -0.249642 -0.249642)
							(end -0.2794 -0.1778)
						)
						(arc
							(start -0.2794 0.1778)
							(mid -0.249642 0.249642)
							(end -0.1778 0.2794)
						)
						(arc
							(start 0.1778 0.2794)
							(mid 0.249642 0.249642)
							(end 0.2794 0.1778)
						)
						(arc
							(start 0.2794 -0.1778)
							(mid 0.249642 -0.249642)
							(end 0.1778 -0.2794)
						)
					)
					(width 0)
					(fill yes)
				)
			)
		)
		(pad "2" smd custom
			(at 0 0.4445 270)
			(size 0.1397 0.1397)
			(layers "F.Cu" "F.Mask" "F.Paste")
			(net "SW_PWR_R_HDD5")
			(options
				(clearance outline)
				(anchor circle)
			)
			(primitives
				(gr_poly
					(pts
						(arc
							(start -0.1778 -0.2794)
							(mid -0.249642 -0.249642)
							(end -0.2794 -0.1778)
						)
						(arc
							(start -0.2794 0.1778)
							(mid -0.249642 0.249642)
							(end -0.1778 0.2794)
						)
						(arc
							(start 0.1778 0.2794)
							(mid 0.249642 0.249642)
							(end 0.2794 0.1778)
						)
						(arc
							(start 0.2794 -0.1778)
							(mid 0.249642 -0.249642)
							(end 0.1778 -0.2794)
						)
					)
					(width 0)
					(fill yes)
				)
			)
		)
	)
	(footprint ""
		(layer "F.Cu")
		(at 77.851 -150.622 -90)
		(property "Reference" "C216"
			(at 0 0 270)
			(layer "F.SilkS")
			(hide yes)
			(effects
				(font
					(size 1.27 1.27)
				)
			)
		)
		(property "Value" "SC4D7U25V5KX-1-GP"
			(at -0.0762 -6.1214 270)
			(unlocked yes)
			(layer "F.Fab")
			(hide yes)
			(effects
				(font
					(size 1.016 1.016)
					(thickness 0.1524)
				)
			)
		)
		(property "Device Type" "C805H58"
			(at -0.0762 -8.1534 270)
			(unlocked yes)
			(layer "F.Fab")
			(hide yes)
			(effects
				(font
					(size 1.016 1.016)
					(thickness 0.1524)
				)
			)
		)
		(duplicate_pad_numbers_are_jumpers no)
		(fp_line
			(start 0.635 0)
			(end -0.635 0)
			(stroke
				(width 0.508)
				(type default)
			)
			(layer "F.SilkS")
		)
		(fp_rect
			(start -0.9652 1.778)
			(end 0.9652 -1.778)
			(stroke
				(width 0)
				(type default)
			)
			(fill no)
			(layer "F.CrtYd")
		)
		(fp_poly
			(pts
				(xy -0.9652 -1.778) (xy 0.9652 -1.778) (xy 0.9652 1.778) (xy -0.9652 1.778)
			)
			(stroke
				(width 0)
				(type default)
			)
			(fill no)
			(layer "F.Fab")
		)
		(pad "1" smd rect
			(at 0 -0.9652 270)
			(size 1.397 1.143)
			(layers "F.Cu" "F.Mask" "F.Paste")
			(net "P12V_HDD14")
		)
		(pad "2" smd rect
			(at 0 0.9652 270)
			(size 1.397 1.143)
			(layers "F.Cu" "F.Mask" "F.Paste")
			(net "GND")
		)
	)
)
